# BASEBOARD_FAB2 (Tioga Pass) — schematic netlist excerpt (pin names and nets, part order shuffled) for the footprints in the layout excerpt that follows; sources: Cadence DE-HDL packaged netlist, KiCad conversion of Wiwynn_Tioga_Pass_MB.brd

J6M1  SCONN288_H44441003  SCONN  pkg PIP  page 50
  \12v\(1)  = P12V_NVDIMM_DEF
  VSS(93)  = GND
  DQ(4)  = M_D_DQ<4>
  VSS(92)  = GND
  DQ(0)  = M_D_DQ<0>
  VSS(91)  = GND
  DQS9P  = M_D_DQS_DP<9>
  DQS9N  = M_D_DQS_DN<9>
  VSS(90)  = GND
  DQ(6)  = M_D_DQ<6>
  VSS(89)  = GND
  DQ(2)  = M_D_DQ<2>
  VSS(88)  = GND
  DQ(12)  = M_D_DQ<12>
  VSS(87)  = GND
  DQ(8)  = M_D_DQ<8>
  VSS(86)  = GND
  DQS10P  = M_D_DQS_DP<10>
  DQS10N  = M_D_DQS_DN<10>
  VSS(85)  = GND
  DQ(14)  = M_D_DQ<14>
  VSS(84)  = GND
  DQ(10)  = M_D_DQ<10>
  VSS(83)  = GND
  DQ(20)  = M_D_DQ<20>
  VSS(82)  = GND
  DQ(16)  = M_D_DQ<16>
  VSS(81)  = GND
  DQS11P  = M_D_DQS_DP<11>
  DQS11N  = M_D_DQS_DN<11>
  VSS(80)  = GND
  DQ(22)  = M_D_DQ<22>
  VSS(79)  = GND
  DQ(18)  = M_D_DQ<18>
  VSS(78)  = GND
  DQ(28)  = M_D_DQ<28>
  VSS(77)  = GND
  DQ(24)  = M_D_DQ<24>
  VSS(76)  = GND
  DQS12P  = M_D_DQS_DP<12>
  DQS12N  = M_D_DQS_DN<12>
  VSS(75)  = GND
  DQ(30)  = M_D_DQ<30>
  VSS(74)  = GND
  DQ(26)  = M_D_DQ<26>
  VSS(73)  = GND
  CB(4)  = M_D_ECC<4>
  VSS(72)  = GND
  CB(0)  = M_D_ECC<0>
  VSS(71)  = GND
  DQS17P  = M_D_DQS_DP<17>
  DQS17N  = M_D_DQS_DN<17>
  VSS(70)  = GND
  CB(6)  = M_D_ECC<6>
  VSS(69)  = GND
  CB(2)  = M_D_ECC<2>
  VSS(68)  = GND
  RESET_N  = M_DEF_RST_N
  VDD(25)  = PVDDQ_DEF
  CKE(0)  = M_D_CKE<2>
  VDD(24)  = PVDDQ_DEF
  ACT_N  = M_D_ACT_N
  BG(0)  = M_D_BG<0>
  VDD(23)  = PVDDQ_DEF
  A12  = M_D_MA<12>
  A9  = M_D_MA<9>
  VDD(22)  = PVDDQ_DEF
  A8  = M_D_MA<8>
  A6  = M_D_MA<6>
  VDD(21)  = PVDDQ_DEF
  A3  = M_D_MA<3>
  A1  = M_D_MA<1>
  VDD(20)  = PVDDQ_DEF
  CK0P  = M_D_CLK_DP<2>
  CK0N  = M_D_CLK_DN<2>
  VDD(19)  = PVDDQ_DEF
  VTT(1)  = PVTT_DEF
  EVENT_N  = FM_DIMM_EVENT_COD_N
  A0  = M_D_MA<0>
  VDD(18)  = PVDDQ_DEF
  BA(0)  = M_D_BA<0>
  A16_RAS_N  = M_D_MA<16>
  VDD(17)  = PVDDQ_DEF
  S0_N  = M_D_CS_N<4>
  VDD(16)  = PVDDQ_DEF
  A15_CAS_N  = M_D_MA<15>
  ODT(0)  = M_D_ODT<2>
  VDD(15)  = PVDDQ_DEF
  S1_N  = M_D_CS_N<5>
  VDD(14)  = PVDDQ_DEF
  ODT(1)  = M_D_ODT<3>
  VDD(13)  = PVDDQ_DEF
  S2_N_C(0)  = M_D_CS_N<6>
  VSS(67)  = GND
  DQ(36)  = M_D_DQ<36>
  VSS(66)  = GND
  DQ(32)  = M_D_DQ<32>
  VSS(65)  = GND
  DQS13P  = M_D_DQS_DP<13>
  DQS13N  = M_D_DQS_DN<13>
  VSS(64)  = GND
  DQ(38)  = M_D_DQ<38>
  VSS(63)  = GND
  DQ(34)  = M_D_DQ<34>
  VSS(62)  = GND
  DQ(44)  = M_D_DQ<44>
  VSS(61)  = GND
  DQ(40)  = M_D_DQ<40>
  VSS(60)  = GND
  DQS14P  = M_D_DQS_DP<14>
  DQS14N  = M_D_DQS_DN<14>
  VSS(59)  = GND
  DQ(46)  = M_D_DQ<46>
  VSS(58)  = GND
  DQ(42)  = M_D_DQ<42>
  VSS(57)  = GND
  DQ(52)  = M_D_DQ<52>
  VSS(56)  = GND
  DQ(48)  = M_D_DQ<48>
  VSS(55)  = GND
  DQS15P  = M_D_DQS_DP<15>
  DQS15N  = M_D_DQS_DN<15>
  VSS(54)  = GND
  DQ(54)  = M_D_DQ<54>
  VSS(53)  = GND
  DQ(50)  = M_D_DQ<50>
  VSS(52)  = GND
  DQ(60)  = M_D_DQ<60>
  VSS(51)  = GND
  DQ(56)  = M_D_DQ<56>
  VSS(50)  = GND
  DQS16P  = M_D_DQS_DP<16>
  DQS16N  = M_D_DQS_DN<16>
  VSS(49)  = GND
  DQ(62)  = M_D_DQ<62>
  VSS(48)  = GND
  DQ(58)  = M_D_DQ<58>
  VSS(47)  = GND
  SA(0)  = PVPP_DEF
  SA(1)  = GND
  SCL  = SMB_DDR_DEF_VPP_SCL
  VPP(4)  = PVPP_DEF
  VPP(3)  = PVPP_DEF
  RFU(2)  = TP_CH_D_DIMM_D1_RFU_2
  \12v\(0)  = P12V_NVDIMM_DEF
  VREFCA  = M_D_VREF
  VSS(46)  = GND
  DQ(5)  = M_D_DQ<5>
  VSS(45)  = GND
  DQ(1)  = M_D_DQ<1>
  VSS(44)  = GND
  DQS0N  = M_D_DQS_DN<0>
  DQS0P  = M_D_DQS_DP<0>
  VSS(43)  = GND
  DQ(7)  = M_D_DQ<7>
  VSS(42)  = GND
  DQ(3)  = M_D_DQ<3>
  VSS(41)  = GND
  DQ(13)  = M_D_DQ<13>
  VSS(40)  = GND
  DQ(9)  = M_D_DQ<9>
  VSS(39)  = GND
  DQS1N  = M_D_DQS_DN<1>
  DQS1P  = M_D_DQS_DP<1>
  VSS(38)  = GND
  DQ(15)  = M_D_DQ<15>
  VSS(37)  = GND
  DQ(11)  = M_D_DQ<11>
  VSS(36)  = GND
  DQ(21)  = M_D_DQ<21>
  VSS(35)  = GND
  DQ(17)  = M_D_DQ<17>
  VSS(34)  = GND
  DQS2N  = M_D_DQS_DN<2>
  DQS2P  = M_D_DQS_DP<2>
  VSS(33)  = GND
  DQ(23)  = M_D_DQ<23>
  VSS(32)  = GND
  DQ(19)  = M_D_DQ<19>
  VSS(31)  = GND
  DQ(29)  = M_D_DQ<29>
  VSS(30)  = GND
  DQ(25)  = M_D_DQ<25>
  VSS(29)  = GND
  DQS3N  = M_D_DQS_DN<3>
  DQS3P  = M_D_DQS_DP<3>
  VSS(28)  = GND
  DQ(31)  = M_D_DQ<31>
  VSS(27)  = GND
  DQ(27)  = M_D_DQ<27>
  VSS(26)  = GND
  CB(5)  = M_D_ECC<5>
  VSS(25)  = GND
  CB(1)  = M_D_ECC<1>
  VSS(24)  = GND
  DQS8N  = M_D_DQS_DN<8>
  DQS8P  = M_D_DQS_DP<8>
  VSS(23)  = GND
  CB(7)  = M_D_ECC<7>
  VSS(22)  = GND
  CB(3)  = M_D_ECC<3>
  VSS(21)  = GND
  CKE(1)  = M_D_CKE<3>
  VDD(12)  = PVDDQ_DEF
  RFU(0)  = TP_CH_D_DIMM_D1_RFU_0
  VDD(11)  = PVDDQ_DEF
  BG(1)  = M_D_BG<1>
  ALERT_N  = M_D_ALERT_N
  VDD(10)  = PVDDQ_DEF
  A11  = M_D_MA<11>
  A7  = M_D_MA<7>
  VDD(9)  = PVDDQ_DEF
  A5  = M_D_MA<5>
  A4  = M_D_MA<4>
  VDD(8)  = PVDDQ_DEF
  A2  = M_D_MA<2>
  VDD(7)  = PVDDQ_DEF
  CK1P  = M_D_CLK_DP<3>
  CK1N  = M_D_CLK_DN<3>
  VDD(6)  = PVDDQ_DEF
  VTT(0)  = PVTT_DEF
  PAR  = M_D_PAR
  VDD(5)  = PVDDQ_DEF
  BA(1)  = M_D_BA<1>
  A10  = M_D_MA<10>
  VDD(4)  = PVDDQ_DEF
  RFU(1)  = TP_CH_D_DIMM_D1_RFU_1
  A14_WE_N  = M_D_MA<14>
  VDD(3)  = PVDDQ_DEF
  SAVE_N_NC  = FM_ADR_COMPLETE_DEF_N
  VDD(2)  = PVDDQ_DEF
  A13  = M_D_MA<13>
  VDD(1)  = PVDDQ_DEF
  A17  = M_D_MA<17>
  C(2)  = M_D_C<2>
  VDD(0)  = PVDDQ_DEF
  S3_N_C(1)  = M_D_CS_N<7>
  SA(2)  = GND
  VSS(20)  = GND
  DQ(37)  = M_D_DQ<37>
  VSS(19)  = GND
  DQ(33)  = M_D_DQ<33>
  VSS(18)  = GND
  DQS4N  = M_D_DQS_DN<4>
  DQS4P  = M_D_DQS_DP<4>
  VSS(17)  = GND
  DQ(39)  = M_D_DQ<39>
  VSS(16)  = GND
  DQ(35)  = M_D_DQ<35>
  VSS(15)  = GND
  DQ(45)  = M_D_DQ<45>
  VSS(14)  = GND
  DQ(41)  = M_D_DQ<41>
  VSS(13)  = GND
  DQS5N  = M_D_DQS_DN<5>
  DQS5P  = M_D_DQS_DP<5>
  VSS(12)  = GND
  DQ(47)  = M_D_DQ<47>
  VSS(11)  = GND
  DQ(43)  = M_D_DQ<43>
  VSS(10)  = GND
  DQ(53)  = M_D_DQ<53>
  VSS(9)  = GND
  DQ(49)  = M_D_DQ<49>
  VSS(8)  = GND
  DQS6N  = M_D_DQS_DN<6>
  DQS6P  = M_D_DQS_DP<6>
  VSS(7)  = GND
  DQ(55)  = M_D_DQ<55>
  VSS(6)  = GND
  DQ(51)  = M_D_DQ<51>
  VSS(5)  = GND
  DQ(61)  = M_D_DQ<61>
  VSS(4)  = GND
  DQ(57)  = M_D_DQ<57>
  VSS(3)  = GND
  DQS7N  = M_D_DQS_DN<7>
  DQS7P  = M_D_DQS_DP<7>
  VSS(2)  = GND
  DQ(63)  = M_D_DQ<63>
  VSS(1)  = GND
  DQ(59)  = M_D_DQ<59>
  VSS(0)  = GND
  VDDSPD  = PVPP_DEF
  SDA  = SMB_DDR_DEF_VPP_SDA
  VPP(1)  = PVPP_DEF
  VPP(0)  = PVPP_DEF
  VPP(2)  = PVPP_DEF

(kicad_pcb
	(version 20260206)
	(generator "pcbnew")
	(generator_version "10.0")
	(general
		(thickness 1.6)
		(legacy_teardrops no)
	)
	(paper "A4")
	(title_block
		(title "Wiwynn_Tioga_Pass_MB.brd")
		(comment 1 "Tioga Pass / footprint 3254 of 4770 (J6M1), pads 250-291 of 291")
	)
	(layers
		(0 "F.Cu" signal "TOP")
		(4 "In1.Cu" signal "L2GND")
		(6 "In2.Cu" signal "L3")
		(8 "In3.Cu" signal "L4GND")
		(10 "In4.Cu" signal "L5")
		(12 "In5.Cu" signal "L6GND")
		(14 "In6.Cu" signal "L7VCC")
		(16 "In7.Cu" signal "L8VCC")
		(18 "In8.Cu" signal "L9GND")
		(20 "In9.Cu" signal "L10")
		(22 "In10.Cu" signal "L11GND")
		(24 "In11.Cu" signal "L12")
		(26 "In12.Cu" signal "L13GND")
		(2 "B.Cu" signal "BOTTOM")
		(9 "F.Adhes" user "F.Adhesive")
		(11 "B.Adhes" user "B.Adhesive")
		(13 "F.Paste" user "Package Geometry/Pastemask Top")
		(15 "B.Paste" user "Package Geometry/Pastemask Bottom")
		(5 "F.SilkS" user "Ref Des/Silkscreen Top")
		(7 "B.SilkS" user "Ref Des/Silkscreen Bottom")
		(1 "F.Mask" user "Board Geometry/Soldermask Top")
		(3 "B.Mask" user "Board Geometry/Soldermask Bottom")
		(17 "Dwgs.User" user "User.Drawings")
		(19 "Cmts.User" user "User.Comments")
		(21 "Eco1.User" user "User.Eco1")
		(23 "Eco2.User" user "User.Eco2")
		(25 "Edge.Cuts" user "Board Geometry/Outline")
		(27 "Margin" user)
		(31 "F.CrtYd" user "Package Geometry/Place Bound Top")
		(29 "B.CrtYd" user "Package Geometry/Place Bound Bottom")
		(35 "F.Fab" user "Ref Des/Assembly Top")
		(33 "B.Fab" user "Ref Des/Assembly Bottom")
	)
	(footprint ""
		(layer "B.Cu")
		(at 194.700398 -132.876036 90)
		(property "Reference" "J6M1"
			(at 2.352548 37.96411 0)
			(unlocked yes)
			(layer "B.SilkS")
			(effects
				(font
					(size 0.7874 0.5842)
					(thickness 0.1524)
				)
				(justify left mirror)
			)
		)
		(property "Value" ""
			(at 0 0 90)
			(layer "B.Fab")
			(effects
				(font
					(size 1.27 1.27)
				)
				(justify mirror)
			)
		)
		(duplicate_pad_numbers_are_jumpers no)
		(pad "247" smd rect
			(at -4.59994 91.799918 270)
			(size 1.8034 0.508)
			(layers "B.Cu" "B.Mask" "B.Paste")
			(net "M_D_DQ<39>")
		)
		(pad "248" smd rect
			(at -4.59994 92.650056 270)
			(size 1.8034 0.508)
			(layers "B.Cu" "B.Mask" "B.Paste")
			(net "GND")
		)
		(pad "249" smd rect
			(at -4.59994 93.49994 270)
			(size 1.8034 0.508)
			(layers "B.Cu" "B.Mask" "B.Paste")
			(net "M_D_DQ<35>")
		)
		(pad "250" smd rect
			(at -4.59994 94.350078 270)
			(size 1.8034 0.508)
			(layers "B.Cu" "B.Mask" "B.Paste")
			(net "GND")
		)
		(pad "251" smd rect
			(at -4.59994 95.199962 270)
			(size 1.8034 0.508)
			(layers "B.Cu" "B.Mask" "B.Paste")
			(net "M_D_DQ<45>")
		)
		(pad "252" smd rect
			(at -4.59994 96.0501 270)
			(size 1.8034 0.508)
			(layers "B.Cu" "B.Mask" "B.Paste")
			(net "GND")
		)
		(pad "253" smd rect
			(at -4.59994 96.899984 270)
			(size 1.8034 0.508)
			(layers "B.Cu" "B.Mask" "B.Paste")
			(net "M_D_DQ<41>")
		)
		(pad "254" smd rect
			(at -4.59994 97.750122 270)
			(size 1.8034 0.508)
			(layers "B.Cu" "B.Mask" "B.Paste")
			(net "GND")
		)
		(pad "255" smd rect
			(at -4.59994 98.600006 270)
			(size 1.8034 0.508)
			(layers "B.Cu" "B.Mask" "B.Paste")
			(net "M_D_DQS_DN<5>")
		)
		(pad "256" smd rect
			(at -4.59994 99.44989 270)
			(size 1.8034 0.508)
			(layers "B.Cu" "B.Mask" "B.Paste")
			(net "M_D_DQS_DP<5>")
		)
		(pad "257" smd rect
			(at -4.59994 100.300028 270)
			(size 1.8034 0.508)
			(layers "B.Cu" "B.Mask" "B.Paste")
			(net "GND")
		)
		(pad "258" smd rect
			(at -4.59994 101.149912 270)
			(size 1.8034 0.508)
			(layers "B.Cu" "B.Mask" "B.Paste")
			(net "M_D_DQ<47>")
		)
		(pad "259" smd rect
			(at -4.59994 102.00005 270)
			(size 1.8034 0.508)
			(layers "B.Cu" "B.Mask" "B.Paste")
			(net "GND")
		)
		(pad "260" smd rect
			(at -4.59994 102.849934 270)
			(size 1.8034 0.508)
			(layers "B.Cu" "B.Mask" "B.Paste")
			(net "M_D_DQ<43>")
		)
		(pad "261" smd rect
			(at -4.59994 103.700072 270)
			(size 1.8034 0.508)
			(layers "B.Cu" "B.Mask" "B.Paste")
			(net "GND")
		)
		(pad "262" smd rect
			(at -4.59994 104.549956 270)
			(size 1.8034 0.508)
			(layers "B.Cu" "B.Mask" "B.Paste")
			(net "M_D_DQ<53>")
		)
		(pad "263" smd rect
			(at -4.59994 105.400094 270)
			(size 1.8034 0.508)
			(layers "B.Cu" "B.Mask" "B.Paste")
			(net "GND")
		)
		(pad "264" smd rect
			(at -4.59994 106.249978 270)
			(size 1.8034 0.508)
			(layers "B.Cu" "B.Mask" "B.Paste")
			(net "M_D_DQ<49>")
		)
		(pad "265" smd rect
			(at -4.59994 107.100116 270)
			(size 1.8034 0.508)
			(layers "B.Cu" "B.Mask" "B.Paste")
			(net "GND")
		)
		(pad "266" smd rect
			(at -4.59994 107.95 270)
			(size 1.8034 0.508)
			(layers "B.Cu" "B.Mask" "B.Paste")
			(net "M_D_DQS_DN<6>")
		)
		(pad "267" smd rect
			(at -4.59994 108.799884 270)
			(size 1.8034 0.508)
			(layers "B.Cu" "B.Mask" "B.Paste")
			(net "M_D_DQS_DP<6>")
		)
		(pad "268" smd rect
			(at -4.59994 109.650022 270)
			(size 1.8034 0.508)
			(layers "B.Cu" "B.Mask" "B.Paste")
			(net "GND")
		)
		(pad "269" smd rect
			(at -4.59994 110.499906 270)
			(size 1.8034 0.508)
			(layers "B.Cu" "B.Mask" "B.Paste")
			(net "M_D_DQ<55>")
		)
		(pad "270" smd rect
			(at -4.59994 111.350044 270)
			(size 1.8034 0.508)
			(layers "B.Cu" "B.Mask" "B.Paste")
			(net "GND")
		)
		(pad "271" smd rect
			(at -4.59994 112.199928 270)
			(size 1.8034 0.508)
			(layers "B.Cu" "B.Mask" "B.Paste")
			(net "M_D_DQ<51>")
		)
		(pad "272" smd rect
			(at -4.59994 113.050066 270)
			(size 1.8034 0.508)
			(layers "B.Cu" "B.Mask" "B.Paste")
			(net "GND")
		)
		(pad "273" smd rect
			(at -4.59994 113.89995 270)
			(size 1.8034 0.508)
			(layers "B.Cu" "B.Mask" "B.Paste")
			(net "M_D_DQ<61>")
		)
		(pad "274" smd rect
			(at -4.59994 114.750088 270)
			(size 1.8034 0.508)
			(layers "B.Cu" "B.Mask" "B.Paste")
			(net "GND")
		)
		(pad "275" smd rect
			(at -4.59994 115.599972 270)
			(size 1.8034 0.508)
			(layers "B.Cu" "B.Mask" "B.Paste")
			(net "M_D_DQ<57>")
		)
		(pad "276" smd rect
			(at -4.59994 116.45011 270)
			(size 1.8034 0.508)
			(layers "B.Cu" "B.Mask" "B.Paste")
			(net "GND")
		)
		(pad "277" smd rect
			(at -4.59994 117.299994 270)
			(size 1.8034 0.508)
			(layers "B.Cu" "B.Mask" "B.Paste")
			(net "M_D_DQS_DN<7>")
		)
		(pad "278" smd rect
			(at -4.59994 118.149878 270)
			(size 1.8034 0.508)
			(layers "B.Cu" "B.Mask" "B.Paste")
			(net "M_D_DQS_DP<7>")
		)
		(pad "279" smd rect
			(at -4.59994 119.000016 270)
			(size 1.8034 0.508)
			(layers "B.Cu" "B.Mask" "B.Paste")
			(net "GND")
		)
		(pad "280" smd rect
			(at -4.59994 119.8499 270)
			(size 1.8034 0.508)
			(layers "B.Cu" "B.Mask" "B.Paste")
			(net "M_D_DQ<63>")
		)
		(pad "281" smd rect
			(at -4.59994 120.700038 270)
			(size 1.8034 0.508)
			(layers "B.Cu" "B.Mask" "B.Paste")
			(net "GND")
		)
		(pad "282" smd rect
			(at -4.59994 121.549922 270)
			(size 1.8034 0.508)
			(layers "B.Cu" "B.Mask" "B.Paste")
			(net "M_D_DQ<59>")
		)
		(pad "283" smd rect
			(at -4.59994 122.40006 270)
			(size 1.8034 0.508)
			(layers "B.Cu" "B.Mask" "B.Paste")
			(net "GND")
		)
		(pad "284" smd rect
			(at -4.59994 123.249944 270)
			(size 1.8034 0.508)
			(layers "B.Cu" "B.Mask" "B.Paste")
			(net "PVPP_DEF")
		)
		(pad "285" smd rect
			(at -4.59994 124.100082 270)
			(size 1.8034 0.508)
			(layers "B.Cu" "B.Mask" "B.Paste")
			(net "SMB_DDR_DEF_VPP_SDA")
		)
		(pad "286" smd rect
			(at -4.59994 124.949966 270)
			(size 1.8034 0.508)
			(layers "B.Cu" "B.Mask" "B.Paste")
			(net "PVPP_DEF")
		)
		(pad "287" smd rect
			(at -4.59994 125.800104 270)
			(size 1.8034 0.508)
			(layers "B.Cu" "B.Mask" "B.Paste")
			(net "PVPP_DEF")
		)
		(pad "288" smd rect
			(at -4.59994 126.649988 270)
			(size 1.8034 0.508)
			(layers "B.Cu" "B.Mask" "B.Paste")
			(net "PVPP_DEF")
		)
	)
)
